P  UNITS CUST 0
C   
C   IPC 356 OUTPUT.  
C
327$NONE$                             A01X+012806Y+003025X0160Y0480     S0      
327$NONE$                             A01X+011606Y+003025X0160Y0480     S0      
327$NONE$                             A01X+009406Y+003475X0160Y0480     S0      
327$NONE$                             A01X+006875Y+003206X0480Y0160     S0      
317$NONE$                       D1650PA00X+001772Y+001969               S0      
317$NONE$                       D1650PA00X+015945Y+001969               S0      
327$NONE$                             A01X+004264Y+005022X0120Y0330     S0      
327$NONE$                             A01X+004658Y+005022X0120Y0330     S0      
327$NONE$                             A01X+004854Y+004368X0120Y0330     S0      
327$NONE$                             A01X+004461Y+004368X0120Y0330     S0      
327$NONE$                             A01X+004067Y+004368X0120Y0330     S0      
327$NONE$                             A01X+003673Y+004368X0120Y0330     S0      
317$NONE$                       D0260PA00X+002689Y+004695               S0      
317$NONE$                       D0230PA00X+005642Y+004695               S0      
317$NONE$                       D0400PA01X+014100Y+004300               S0      
317$NONE$                       D0400PA01X+002583Y-000949               S0      
317$NONE$                       D0400PA01X+051923Y-000949               S0      
317$NONE$                       D0860PA00X+016450Y+004850               S0      
317$NONE$                       D0860PA00X+000900Y+004800               S0      
327$NONE$                             A06X+008506Y+003125X0160Y0480     S0      
327$NONE$                             A06X+007994Y+005325X0160Y0480     S0      
317$NONE$                       D0400PA00X+010364Y+004390               S0      
317$NONE$                       D0400PA00X+012726Y+004390               S0      
317$NONE$           VIA        MD0400PA06X+014850Y+004750               S0      
317P5V_VGA                      D0240PA01X+006450Y+004220               S0      
327P5V_VGA                            A01X+007100Y+004280X0630Y0380     S0      
327P5V_VGA                            A01X+003083Y+005022X0120Y0330     S0      
327P5V_VGA                            A01X+005248Y+004368X0120Y0330     S0      
317P5V_VGA          VIA        MD0260PA01X+007800Y+004250               S0      
317P5V_VGA          VIA        MD0100PA00X+003083Y+004707               S0      
317P5V_VGA          VIA        MD0100PA00X+005800Y+003850               S0      
327GND                                A01X+012294Y+003025X0160Y0480     S0      
327GND                                A01X+011094Y+003025X0160Y0480     S0      
327GND                                A01X+008894Y+003475X0160Y0480     S0      
327GND                                A01X+006875Y+002694X0480Y0160     S0      
317GND                          D0240PA01X+006450Y+004580               S0      
317GND                          D0200PA00X+002880Y+002608               S0      
317GND                          D0200PA00X+002412Y+003077               S0      
317GND                          D0200PA00X+001132Y+003077               S0      
317GND                          D0200PA00X+000663Y+002608               S0      
317GND                          D0200PA00X+000663Y+001329               S0      
317GND                          D0200PA00X+001132Y+000860               S0      
317GND                          D0200PA00X+002412Y+000860               S0      
317GND                          D0200PA00X+002880Y+001329               S0      
317GND                          D0200PA00X+017053Y+002608               S0      
317GND                          D0200PA00X+016585Y+003077               S0      
317GND                          D0200PA00X+015305Y+003077               S0      
317GND                          D0200PA00X+014836Y+002608               S0      
317GND                          D0200PA00X+014836Y+001329               S0      
317GND                          D0200PA00X+015305Y+000860               S0      
317GND                          D0200PA00X+016585Y+000860               S0      
317GND                          D0200PA00X+017053Y+001329               S0      
317GND                          D0200PA01X+002681Y+005089               S0      
317GND                          D0280PA00X+003221Y+005541               S0      
327GND                                A01X+003693Y+005541X0320Y0220     S0      
327GND                                A01X+004165Y+005541X0320Y0220     S0      
327GND                                A01X+004638Y+005541X0320Y0220     S0      
317GND                          D0280PA00X+005110Y+005541               S0      
317GND                          D0200PA01X+005650Y+005089               S0      
317GND                          D0200PA01X+005650Y+004301               S0      
317GND                          D0280PA00X+005110Y+003848               S0      
327GND                                A01X+004638Y+003848X0320Y0220     S0      
327GND                                A01X+004165Y+003848X0320Y0220     S0      
327GND                                A01X+003693Y+003848X0320Y0220     S0      
317GND                          D0280PA00X+003221Y+003848               S0      
317GND                          D0200PA01X+002681Y+004301               S0      
327GND                                A01X+003476Y+005022X0120Y0330     S0      
327GND                                A01X+003870Y+005022X0120Y0330     S0      
327GND                                A06X+013200Y+002100X0400Y0220     S0      
327GND                                A06X+007994Y+003125X0160Y0480     S0      
327GND                                A06X+008506Y+005325X0160Y0480     S0      
327GND                                A06X+007284Y+000610X0240Y0630     S0      
327GND                                A06X+004528Y+000610X0240Y0630     S0      
327GND                                A06X+010551Y+001614X0320Y0710     S0      
327GND                                A06X+004016Y+001614X0320Y0710     S0      
317GND                          D0240PA06X+013100Y+001280               S0      
317GND                          D0240PA06X+012750Y+001280               S0      
327GND                                A06X+010758Y+005226X0390Y1080     S0      
327GND                                A06X+012333Y+005226X0390Y1080     S0      
317GND              VIA        MD0240PA06X+015600Y+005350               S0      
317GND              VIA        MD0100PA00X+010366Y+005226               S0      
317GND              VIA        MD0100PA00X+010814Y+002813               S0      
317GND              VIA        MD0100PA00X+011940Y+002980               S0      
317GND              VIA        MD0100PA00X+011940Y+005226               S0      
317GND              VIA        MD0100PA00X+013550Y+004500               S0      
317GND              VIA        MD0100PA00X+013700Y+001275               S0      
317GND              VIA        MD0100PA00X+014300Y+000500               S0      
317GND              VIA        MD0100PA00X+014500Y+003650               S0      
317GND              VIA        MD0100PA00X+014500Y+005500               S0      
317GND              VIA        MD0100PA00X+001500Y+004500               S0      
317GND              VIA        MD0100PA00X+015500Y+004500               S0      
317GND              VIA        MD0100PA00X+016500Y+005500               S0      
317GND              VIA        MD0100PA00X+017000Y+004500               S0      
317GND              VIA        MD0100PA00X+002000Y+005500               S0      
317GND              VIA        MD0100PA00X+003500Y+000500               S0      
317GND              VIA        MD0100PA00X+004010Y+002169               S0      
317GND              VIA        MD0100PA00X+004120Y+000740               S0      
317GND              VIA        MD0100PA00X+000500Y+003800               S0      
317GND              VIA        MD0100PA00X+000500Y+005500               S0      
317GND              VIA        MD0100PA00X+006130Y+004725               S0      
317GND              VIA        MD0100PA00X+006875Y+002410               S0      
317GND              VIA        MD0100PA00X+007070Y+001120               S0      
317GND              VIA        MD0100PA00X+007994Y+002685               S0      
317GND              VIA        MD0100PA00X+008790Y+005310               S0      
317GND              VIA        MD0100PA00X+008894Y+003940               S0      
317GND              VIA        MD0100PA00X+009820Y+001650               S0      
327P5V                                A01X+008900Y+004900X0400Y0220     S0      
317P5V                          D0340PA06X+011020Y+002410               S0      
317P5V                          D0240PA06X+011395Y+001100               S0      
327P5V                                A06X+010039Y+000610X0240Y0630     S0      
327P5V                                A06X+009971Y+003553X0390Y1080     S0      
317P5V              VIA        MD0240PA06X+011300Y+001930               S0      
317P5V              VIA        MD0100PA00X+009300Y+004970               S0      
317P5V              VIA        MD0100PA00X+009480Y+004680               S0      
327HBA_PRSNT0_N                       A01X+011811Y+000446X0730Y0490     S0      
327HBA_PRSNT0_N                       A06X+009646Y+000610X0240Y0630     S0      
317HBA_PRSNT0_N     VIA        MD0100PA00X+010900Y+001100               S0      
327HBA_PRSNT1_N                       A01X+010394Y+000446X0730Y0490     S0      
327HBA_PRSNT1_N                       A06X+009252Y+000610X0240Y0630     S0      
317HBA_PRSNT1_N     VIA        MD0100PA00X+009540Y+001250               S0      
327HBA_PRSNT2_N                       A01X+008976Y+000446X0730Y0490     S0      
327HBA_PRSNT2_N                       A06X+008858Y+000610X0240Y0630     S0      
317HBA_PRSNT2_N     VIA        MD0100PA00X+008410Y+001490               S0      
327HBA_PRSNT3_N                       A01X+007559Y+000446X0730Y0490     S0      
327HBA_PRSNT3_N                       A06X+008465Y+000610X0240Y0630     S0      
317HBA_PRSNT3_N     VIA        MD0100PA00X+008150Y+001270               S0      
327HBA_PRSNT4_N                       A01X+006142Y+000446X0730Y0490     S0      
327HBA_PRSNT4_N                       A06X+008071Y+000610X0240Y0630     S0      
317HBA_PRSNT4_N     VIA        MD0100PA00X+007420Y+002170               S0      
327HBA_PRSNT5_N                       A01X+004724Y+000446X0730Y0490     S0      
327HBA_PRSNT5_N                       A06X+007677Y+000610X0240Y0630     S0      
317HBA_PRSNT5_N     VIA        MD0100PA00X+005344Y+001390               S0      
317HBA_PRSNT5_N     VIA        MD0100PA00X+007141Y+001961               S0      
317HDD_ACT_LED0                 D0220PA01X+013350Y+001880               S0      
327HDD_ACT_LED0                       A06X+006890Y+000610X0240Y0630     S0      
317HDD_ACT_LED0     VIA        MD0100PA00X+013350Y+001570               S0      
317HDD_ACT_LED0     VIA        MD0100PA00X+006850Y+001380               S0      
317HDD_ACT_LED1                 D0220PA01X+010130Y+002550               S0      
327HDD_ACT_LED1                       A06X+006496Y+000610X0240Y0630     S0      
317HDD_ACT_LED1     VIA        MD0100PA00X+006900Y+001720               S0      
317HDD_ACT_LED1     VIA        MD0100PA00X+009800Y+002550               S0      
317HDD_ACT_LED2                 D0220PA01X+008350Y+002980               S0      
327HDD_ACT_LED2                       A06X+006102Y+000610X0240Y0630     S0      
317HDD_ACT_LED2     VIA        MD0100PA00X+008470Y+002670               S0      
317HDD_ACT_LED3                 D0220PA01X+006220Y+002500               S0      
327HDD_ACT_LED3                       A06X+005709Y+000610X0240Y0630     S0      
317HDD_ACT_LED3     VIA        MD0100PA00X+006530Y+002444               S0      
327HDD_ACT_LED4                       A06X+005315Y+000610X0240Y0630     S0      
317HDD_ACT_LED4                 D0220PA06X+006690Y+002750               S0      
327HDD_ACT_LED5                       A06X+004921Y+000610X0240Y0630     S0      
317HDD_ACT_LED5                 D0220PA06X+007000Y+004830               S0      
317HDD_ACT_LED5     VIA        MD0240PA06X+006300Y+003900               S0      
327CRT_R0_OUT                         A01X+004461Y+005022X0120Y0330     S0      
327CRT_R0_OUT                         A01X+003870Y+004368X0120Y0330     S0      
327CRT_R0_OUT                         A06X+009971Y+005226X0390Y1080     S0      
317CRT_R0_OUT       VIA        MD0100PA00X+009600Y+005560               S0      
317CRT_R0_OUT       VIA        MD0100PA00X+003940Y+004683               S0      
317CRT_R0_OUT       VIA        MD0100PA00X+004461Y+004683               S0      
327CRT_G0_OUT                         A01X+004067Y+005022X0120Y0330     S0      
327CRT_G0_OUT                         A01X+004264Y+004368X0120Y0330     S0      
327CRT_G0_OUT                         A06X+011545Y+005226X0390Y1080     S0      
317CRT_G0_OUT       VIA        MD0100PA00X+011180Y+005226               S0      
327CRT_B0_OUT                         A01X+003673Y+005022X0120Y0330     S0      
327CRT_B0_OUT                         A01X+004658Y+004368X0120Y0330     S0      
327CRT_B0_OUT                         A06X+013120Y+005226X0390Y1080     S0      
317CRT_B0_OUT       VIA        MD0100PA00X+012750Y+005226               S0      
317CRT_B0_OUT       VIA        MD0100PA00X+003673Y+004707               S0      
317CRT_B0_OUT       VIA        MD0100PA00X+004525Y+003585               S0      
327CRT_SDA                            A01X+005051Y+005022X0120Y0330     S0      
327CRT_SDA                            A01X+003280Y+004368X0120Y0330     S0      
327CRT_SDA                            A06X+010758Y+003553X0390Y1080     S0      
317CRT_SDA          VIA        MD0260PA01X+009900Y+004650               S0      
317CRT_SDA          VIA        MD0100PA00X+010370Y+003640               S0      
317CRT_SDA          VIA        MD0100PA00X+003420Y+004700               S0      
317CRT_SDA          VIA        MD0100PA00X+005600Y+005550               S0      
327CRT_SCL                            A01X+005248Y+005022X0120Y0330     S0      
327CRT_SCL                            A01X+003083Y+004368X0120Y0330     S0      
327CRT_SCL                            A06X+011545Y+003553X0390Y1080     S0      
317CRT_SCL          VIA        MD0100PA00X+011170Y+003960               S0      
317CRT_SCL          VIA        MD0100PA00X+002810Y+003930               S0      
317CRT_SCL          VIA        MD0100PA00X+005222Y+004707               S0      
327CRTHS_OUT                          A01X+004854Y+005022X0120Y0330     S0      
327CRTHS_OUT                          A01X+003476Y+004368X0120Y0330     S0      
327CRTHS_OUT                          A06X+012333Y+003553X0390Y1080     S0      
317CRTHS_OUT        VIA        MD0100PA00X+011950Y+003390               S0      
317CRTHS_OUT        VIA        MD0100PA00X+003930Y+003550               S0      
317CRTHS_OUT        VIA        MD0100PA00X+004720Y+004707               S0      
327CRTVS_OUT                          A01X+003280Y+005022X0120Y0330     S0      
327CRTVS_OUT                          A01X+005051Y+004368X0120Y0330     S0      
327CRTVS_OUT                          A06X+013120Y+003553X0390Y1080     S0      
317CRTVS_OUT        VIA        MD0100PA00X+012750Y+003700               S0      
317CRTVS_OUT        VIA        MD0100PA00X+002810Y+005530               S0      
317CRTVS_OUT        VIA        MD0100PA00X+004973Y+004682               S0      
327P5V_D                              A01X+008000Y+004900X0400Y0220     S0      
327P5V_D                              A01X+007100Y+005020X0630Y0380     S0      
327HDD_LED_P0                         A01X+012294Y+002375X0160Y0480     S0      
327HDD_LED_P0                         A01X+011811Y+001523X0730Y0490     S0      
317HDD_LED_P0                   D0220PA01X+012600Y+001720               S0      
327HDD_LED_P1                         A01X+011094Y+002375X0160Y0480     S0      
327HDD_LED_P1                         A01X+010394Y+001523X0730Y0490     S0      
317HDD_LED_P1                   D0220PA01X+010520Y+002100               S0      
327HDD_LED_P2                         A01X+008894Y+002825X0160Y0480     S0      
327HDD_LED_P2                         A01X+008976Y+001523X0730Y0490     S0      
317HDD_LED_P2                   D0220PA01X+008880Y+002100               S0      
327HDD_LED_P3                         A01X+007525Y+002694X0480Y0160     S0      
327HDD_LED_P3                         A01X+007559Y+001523X0730Y0490     S0      
317HDD_LED_P3                   D0220PA01X+007730Y+002100               S0      
327HDD_LED_P4                         A01X+006142Y+001523X0730Y0490     S0      
317HDD_LED_P4                   D0220PA01X+006270Y+002100               S0      
327HDD_LED_P4                         A06X+007994Y+003775X0160Y0480     S0      
317HDD_LED_P4       VIA        MD0100PA00X+006580Y+002100               S0      
317HDD_LED_P4       VIA        MD0100PA00X+007600Y+003775               S0      
327HDD_LED_P5                         A01X+004724Y+001523X0730Y0490     S0      
317HDD_LED_P5                   D0220PA01X+004630Y+002100               S0      
327HDD_LED_P5                         A06X+008506Y+004675X0160Y0480     S0      
317HDD_LED_P5       VIA        MD0100PA00X+004600Y+002560               S0      
317HDD_LED_P5       VIA        MD0100PA00X+008770Y+004340               S0      
327P3V3                               A01X+012806Y+002375X0160Y0480     S0      
327P3V3                               A01X+011606Y+002375X0160Y0480     S0      
327P3V3                               A01X+009406Y+002825X0160Y0480     S0      
327P3V3                               A01X+007525Y+003206X0480Y0160     S0      
317P3V3                         D0220PA01X+005430Y+002900               S0      
317P3V3                         D0220PA01X+007980Y+003750               S0      
317P3V3                         D0220PA01X+010130Y+002950               S0      
317P3V3                         D0220PA01X+013350Y+002630               S0      
317P3V3                         D0220PA01X+005930Y+002100               S0      
317P3V3                         D0220PA01X+008070Y+002100               S0      
317P3V3                         D0220PA01X+009220Y+002100               S0      
317P3V3                         D0220PA01X+010180Y+002100               S0      
317P3V3                         D0220PA01X+004970Y+002100               S0      
317P3V3                         D0220PA01X+012600Y+001380               S0      
317P3V3                         D0240PA06X+012105Y+000844               S0      
327P3V3                               A06X+008506Y+003775X0160Y0480     S0      
327P3V3                               A06X+007994Y+004675X0160Y0480     S0      
317P3V3                         D0240PA06X+013100Y+000920               S0      
317P3V3                         D0240PA06X+012750Y+000920               S0      
317P3V3                         D0220PA06X+007400Y+004830               S0      
317P3V3                         D0220PA06X+007450Y+003120               S0      
317P3V3             VIA        MD0240PA06X+007350Y+004200               S0      
317P3V3             VIA        MD0100PA00X+011830Y+001990               S0      
317P3V3             VIA        MD0100PA00X+013100Y+000600               S0      
317P3V3             VIA        MD0100PA00X+013420Y+000900               S0      
317P3V3             VIA        MD0100PA00X+005280Y+002100               S0      
317P3V3             VIA        MD0100PA00X+005450Y+002550               S0      
317P3V3             VIA        MD0100PA00X+005620Y+002100               S0      
317P3V3             VIA        MD0100PA00X+007400Y+003490               S0      
317P3V3             VIA        MD0100PA00X+008510Y+002110               S0      
317P3V3             VIA        MD0100PA00X+009530Y+002100               S0      
317P3V3             VIA        MD0100PA00X+009870Y+002100               S0      
327P5V_R_E1                           A06X+012300Y+002100X0400Y0220     S0      
317P5V_R_E1                     D0340PA06X+011580Y+002410               S0      
317P5V_R_E1                     D0240PA06X+012105Y+001356               S0      
327HDD_LED_A4                         A06X+008250Y+003125X0160Y0480     S0      
317HDD_LED_A4                   D0220PA06X+007450Y+002780               S0      
317HDD_LED_A4                   D0220PA06X+007030Y+002750               S0      
327HDD_LED_A5                         A06X+008250Y+005325X0160Y0480     S0      
317HDD_LED_A5                   D0220PA06X+007400Y+005170               S0      
317HDD_LED_A5                   D0220PA06X+007000Y+005170               S0      
317HDD_LED_A5       VIA        MD0240PA06X+007400Y+005620               S0      
327HDD_LED_A0                         A01X+012550Y+003025X0160Y0480     S0      
317HDD_LED_A0                   D0220PA01X+013350Y+002970               S0      
317HDD_LED_A0                   D0220PA01X+013350Y+002220               S0      
327HDD_LED_A1                         A01X+011350Y+003025X0160Y0480     S0      
317HDD_LED_A1                   D0220PA01X+010470Y+002950               S0      
317HDD_LED_A1                   D0220PA01X+010470Y+002550               S0      
327HDD_LED_A2                         A01X+009150Y+003475X0160Y0480     S0      
317HDD_LED_A2                   D0220PA01X+008320Y+003750               S0      
317HDD_LED_A2                   D0220PA01X+008350Y+003320               S0      
327HDD_LED_A3                         A01X+006875Y+002950X0480Y0160     S0      
317HDD_LED_A3                   D0220PA01X+005770Y+002900               S0      
317HDD_LED_A3                   D0220PA01X+005880Y+002500               S0      
317HDD_LED_A3       VIA        MD0260PA01X+006250Y+002960               S0      
999
